# BASEBOARD_FAB2 (Tioga Pass) — schematic netlist excerpt (pin names and nets, part order shuffled) for the footprints in the layout excerpt that follows; sources: Cadence DE-HDL packaged netlist, KiCad conversion of Wiwynn_Tioga_Pass_MB.brd

C8C15  CAP_A  0.1UF 16V 10% X7R  pkg 0402V  page 188 : A = KR_P0_OCP_RX_DP ; B = KR_P0_OCP_RX_C_DP

(kicad_pcb
	(version 20260206)
	(generator "pcbnew")
	(generator_version "10.0")
	(general
		(thickness 1.6)
		(legacy_teardrops no)
	)
	(paper "A4")
	(title_block
		(title "Wiwynn_Tioga_Pass_MB.brd")
		(comment 1 "Tioga Pass / footprints 240-240 of 4770")
	)
	(layers
		(0 "F.Cu" signal "TOP")
		(4 "In1.Cu" signal "L2GND")
		(6 "In2.Cu" signal "L3")
		(8 "In3.Cu" signal "L4GND")
		(10 "In4.Cu" signal "L5")
		(12 "In5.Cu" signal "L6GND")
		(14 "In6.Cu" signal "L7VCC")
		(16 "In7.Cu" signal "L8VCC")
		(18 "In8.Cu" signal "L9GND")
		(20 "In9.Cu" signal "L10")
		(22 "In10.Cu" signal "L11GND")
		(24 "In11.Cu" signal "L12")
		(26 "In12.Cu" signal "L13GND")
		(2 "B.Cu" signal "BOTTOM")
		(9 "F.Adhes" user "F.Adhesive")
		(11 "B.Adhes" user "B.Adhesive")
		(13 "F.Paste" user "Package Geometry/Pastemask Top")
		(15 "B.Paste" user "Package Geometry/Pastemask Bottom")
		(5 "F.SilkS" user "Ref Des/Silkscreen Top")
		(7 "B.SilkS" user "Ref Des/Silkscreen Bottom")
		(1 "F.Mask" user "Board Geometry/Soldermask Top")
		(3 "B.Mask" user "Board Geometry/Soldermask Bottom")
		(17 "Dwgs.User" user "User.Drawings")
		(19 "Cmts.User" user "User.Comments")
		(21 "Eco1.User" user "User.Eco1")
		(23 "Eco2.User" user "User.Eco2")
		(25 "Edge.Cuts" user "Board Geometry/Outline")
		(27 "Margin" user)
		(31 "F.CrtYd" user "Package Geometry/Place Bound Top")
		(29 "B.CrtYd" user "Package Geometry/Place Bound Bottom")
		(35 "F.Fab" user "Ref Des/Assembly Top")
		(33 "B.Fab" user "Ref Des/Assembly Bottom")
	)
	(footprint ""
		(layer "F.Cu")
		(at 418.7952 -91.7829 -90)
		(property "Reference" "C8C15"
			(at 0 0 270)
			(layer "F.SilkS")
			(hide yes)
			(effects
				(font
					(size 1.27 1.27)
				)
			)
		)
		(property "Value" ""
			(at 0 0 270)
			(layer "F.Fab")
			(effects
				(font
					(size 1.27 1.27)
				)
			)
		)
		(duplicate_pad_numbers_are_jumpers no)
		(fp_poly
			(pts
				(xy 0.3048 -0.1016) (xy 0.3048 0.9906) (xy -0.3048 0.9906) (xy -0.3048 -0.1016)
			)
			(stroke
				(width 0)
				(type default)
			)
			(fill no)
			(layer "F.CrtYd")
		)
		(fp_line
			(start -0.3048 0.9906)
			(end 0.3048 0.9906)
			(stroke
				(width 0.1)
				(type default)
			)
			(layer "F.Fab")
		)
		(fp_line
			(start 0.3048 0.9906)
			(end 0.3048 -0.1016)
			(stroke
				(width 0.1)
				(type default)
			)
			(layer "F.Fab")
		)
		(fp_line
			(start -0.3048 -0.1016)
			(end -0.3048 0.9906)
			(stroke
				(width 0.1)
				(type default)
			)
			(layer "F.Fab")
		)
		(fp_line
			(start 0.3048 -0.1016)
			(end -0.3048 -0.1016)
			(stroke
				(width 0.1)
				(type default)
			)
			(layer "F.Fab")
		)
		(pad "1" smd rect
			(at 0 0 270)
			(size 0.508 0.508)
			(layers "F.Cu" "F.Mask" "F.Paste")
			(net "KR_P0_OCP_RX_DP")
		)
		(pad "2" smd rect
			(at 0 0.889 270)
			(size 0.508 0.508)
			(layers "F.Cu" "F.Mask" "F.Paste")
			(net "KR_P0_OCP_RX_C_DP")
		)
		(zone
			(layer "F.Cu")
			(hatch none 0.5)
			(connect_pads
				(clearance 0)
			)
			(min_thickness 0.25)
			(keepout
				(tracks not_allowed)
				(vias allowed)
				(pads allowed)
				(copperpour not_allowed)
				(footprints allowed)
			)
			(placement
				(enabled no)
				(sheetname "")
			)
			(fill
				(thermal_gap 0.5)
				(thermal_bridge_width 0.5)
				(island_removal_mode 0)
			)
			(polygon
				(pts
					(xy 418.1602 -92.0369) (xy 418.1602 -91.5289) (xy 418.5412 -91.5289) (xy 418.5412 -92.0369)
				)
			)
		)
		(zone
			(layer "F.Cu")
			(hatch none 0.5)
			(connect_pads
				(clearance 0)
			)
			(min_thickness 0.25)
			(keepout
				(tracks allowed)
				(vias not_allowed)
				(pads allowed)
				(copperpour not_allowed)
				(footprints allowed)
			)
			(placement
				(enabled no)
				(sheetname "")
			)
			(fill
				(thermal_gap 0.5)
				(thermal_bridge_width 0.5)
				(island_removal_mode 0)
			)
			(polygon
				(pts
					(xy 418.5412 -92.0369) (xy 418.5412 -91.5289) (xy 418.1602 -91.5289) (xy 418.1602 -92.0369)
				)
			)
		)
	)
)
